(kicad_pcb
	(version 20260206)
	(generator "pcbnew")
	(generator_version "10.0")
	(general
		(thickness 1.6)
		(legacy_teardrops no)
	)
	(paper "A4")
	(title_block
		(title "04192023_DAF0TMB3IC0_F0TG_MB_C_brd_V02_OCP.brd")
		(comment 1 "Grand Teton / footprints 7384-7390 of 8354")
	)
	(layers
		(0 "F.Cu" signal "TOP")
		(4 "In1.Cu" signal "GND")
		(6 "In2.Cu" signal "IN1")
		(8 "In3.Cu" signal "GND1")
		(10 "In4.Cu" signal "IN2")
		(12 "In5.Cu" signal "GND2")
		(14 "In6.Cu" signal "IN3")
		(16 "In7.Cu" signal "GND3")
		(18 "In8.Cu" signal "VCC")
		(20 "In9.Cu" signal "VCC1")
		(22 "In10.Cu" signal "GND4")
		(24 "In11.Cu" signal "IN4")
		(26 "In12.Cu" signal "GND5")
		(28 "In13.Cu" signal "IN5")
		(30 "In14.Cu" signal "GND6")
		(32 "In15.Cu" signal "IN6")
		(34 "In16.Cu" signal "GND7")
		(2 "B.Cu" signal "BOTTOM")
		(9 "F.Adhes" user "F.Adhesive")
		(11 "B.Adhes" user "B.Adhesive")
		(13 "F.Paste" user "Package Geometry/Pastemask Top")
		(15 "B.Paste" user "Package Geometry/Pastemask Bottom")
		(5 "F.SilkS" user "Ref Des/Silkscreen Top")
		(7 "B.SilkS" user "Ref Des/Silkscreen Bottom")
		(1 "F.Mask" user "Board Geometry/Soldermask Top")
		(3 "B.Mask" user "Board Geometry/Soldermask Bottom")
		(17 "Dwgs.User" user "User.Drawings")
		(19 "Cmts.User" user "User.Comments")
		(21 "Eco1.User" user "User.Eco1")
		(23 "Eco2.User" user "User.Eco2")
		(25 "Edge.Cuts" user "Board Geometry/Outline")
		(27 "Margin" user)
		(31 "F.CrtYd" user "Package Geometry/Place Bound Top")
		(29 "B.CrtYd" user "Package Geometry/Place Bound Bottom")
		(35 "F.Fab" user "Ref Des/Assembly Top")
		(33 "B.Fab" user "Ref Des/Assembly Bottom")
	)
	(footprint ""
		(layer "B.Cu")
		(at 231.648 -342.011 90)
		(property "Reference" "R6762"
			(at 0 0 90)
			(layer "B.SilkS")
			(hide yes)
			(effects
				(font
					(size 1.27 1.27)
				)
				(justify mirror)
			)
		)
		(property "Value" ""
			(at 0 0 90)
			(layer "B.Fab")
			(effects
				(font
					(size 1.27 1.27)
				)
				(justify mirror)
			)
		)
		(duplicate_pad_numbers_are_jumpers no)
		(fp_line
			(start 0.32512 -0.175006)
			(end -0.32512 -0.175006)
			(stroke
				(width 0.1)
				(type default)
			)
			(layer "B.Fab")
		)
		(fp_line
			(start -0.32512 -0.175006)
			(end -0.32512 0.175006)
			(stroke
				(width 0.1)
				(type default)
			)
			(layer "B.Fab")
		)
		(fp_line
			(start 0.32512 0.175006)
			(end 0.32512 -0.175006)
			(stroke
				(width 0.1)
				(type default)
			)
			(layer "B.Fab")
		)
		(fp_line
			(start -0.32512 0.175006)
			(end 0.32512 0.175006)
			(stroke
				(width 0.1)
				(type default)
			)
			(layer "B.Fab")
		)
		(pad "1" smd rect
			(at 0.2667 0 270)
			(size 0.3048 0.381)
			(layers "B.Cu" "B.Mask" "B.Paste")
			(net "P1V8_CPU0_RT_1D")
		)
		(pad "2" smd rect
			(at -0.2667 0 90)
			(size 0.3048 0.381)
			(layers "B.Cu" "B.Mask" "B.Paste")
			(net "SMB_RT_CPU0_P0_R_SDA")
		)
	)
	(footprint ""
		(layer "B.Cu")
		(at 110.965996 -26.952448 90)
		(property "Reference" "C6098"
			(at 0 0 90)
			(layer "B.SilkS")
			(hide yes)
			(effects
				(font
					(size 1.27 1.27)
				)
				(justify mirror)
			)
		)
		(property "Value" ""
			(at 0 0 90)
			(layer "B.Fab")
			(effects
				(font
					(size 1.27 1.27)
				)
				(justify mirror)
			)
		)
		(duplicate_pad_numbers_are_jumpers no)
		(fp_line
			(start 0.7874 -0.4064)
			(end -0.7874 -0.4064)
			(stroke
				(width 0.1524)
				(type default)
			)
			(layer "B.SilkS")
		)
		(fp_line
			(start -0.7874 -0.4064)
			(end -0.7874 0.4064)
			(stroke
				(width 0.1524)
				(type default)
			)
			(layer "B.SilkS")
		)
		(fp_line
			(start 0.7874 0.4064)
			(end 0.7874 -0.4064)
			(stroke
				(width 0.1524)
				(type default)
			)
			(layer "B.SilkS")
		)
		(fp_line
			(start -0.7874 0.4064)
			(end 0.7874 0.4064)
			(stroke
				(width 0.1524)
				(type default)
			)
			(layer "B.SilkS")
		)
		(fp_line
			(start 0.67945 -0.305054)
			(end 0.12065 -0.305054)
			(stroke
				(width 0.1)
				(type default)
			)
			(layer "B.Fab")
		)
		(fp_line
			(start 0.12065 -0.305054)
			(end 0.12065 -0.2794)
			(stroke
				(width 0.1)
				(type default)
			)
			(layer "B.Fab")
		)
		(fp_line
			(start -0.12065 -0.3048)
			(end -0.67945 -0.3048)
			(stroke
				(width 0.1)
				(type default)
			)
			(layer "B.Fab")
		)
		(fp_line
			(start -0.67945 -0.3048)
			(end -0.67945 0.3048)
			(stroke
				(width 0.1)
				(type default)
			)
			(layer "B.Fab")
		)
		(fp_line
			(start 0.12065 -0.2794)
			(end -0.12065 -0.2794)
			(stroke
				(width 0.1)
				(type default)
			)
			(layer "B.Fab")
		)
		(fp_line
			(start -0.12065 -0.2794)
			(end -0.12065 -0.3048)
			(stroke
				(width 0.1)
				(type default)
			)
			(layer "B.Fab")
		)
		(fp_line
			(start 0.12065 0.2794)
			(end 0.12065 0.3048)
			(stroke
				(width 0.1)
				(type default)
			)
			(layer "B.Fab")
		)
		(fp_line
			(start -0.120396 0.2794)
			(end 0.12065 0.2794)
			(stroke
				(width 0.1)
				(type default)
			)
			(layer "B.Fab")
		)
		(fp_line
			(start 0.67945 0.3048)
			(end 0.67945 -0.305054)
			(stroke
				(width 0.1)
				(type default)
			)
			(layer "B.Fab")
		)
		(fp_line
			(start 0.12065 0.3048)
			(end 0.67945 0.3048)
			(stroke
				(width 0.1)
				(type default)
			)
			(layer "B.Fab")
		)
		(fp_line
			(start -0.120396 0.3048)
			(end -0.120396 0.2794)
			(stroke
				(width 0.1)
				(type default)
			)
			(layer "B.Fab")
		)
		(fp_line
			(start -0.67945 0.3048)
			(end -0.120396 0.3048)
			(stroke
				(width 0.1)
				(type default)
			)
			(layer "B.Fab")
		)
		(pad "1" smd circle
			(at 0.40005 0 270)
			(size 0 0)
			(layers "B.Cu" "B.Mask" "B.Paste")
			(net "P3V3_AUX_CPU0_USB2_AVDD33")
		)
		(pad "2" smd circle
			(at -0.40005 0 270)
			(size 0 0)
			(layers "B.Cu" "B.Mask" "B.Paste")
			(net "GND")
		)
	)
	(footprint ""
		(layer "B.Cu")
		(at 102.275386 -268.418564)
		(property "Reference" "C2366"
			(at 0 0 0)
			(layer "B.SilkS")
			(hide yes)
			(effects
				(font
					(size 1.27 1.27)
				)
				(justify mirror)
			)
		)
		(property "Value" ""
			(at 0 0 0)
			(layer "B.Fab")
			(effects
				(font
					(size 1.27 1.27)
				)
				(justify mirror)
			)
		)
		(duplicate_pad_numbers_are_jumpers no)
		(fp_line
			(start -0.7874 -0.4064)
			(end -0.7874 0.4064)
			(stroke
				(width 0.1524)
				(type default)
			)
			(layer "B.SilkS")
		)
		(fp_line
			(start -0.7874 0.4064)
			(end 0.7874 0.4064)
			(stroke
				(width 0.1524)
				(type default)
			)
			(layer "B.SilkS")
		)
		(fp_line
			(start 0.7874 -0.4064)
			(end -0.7874 -0.4064)
			(stroke
				(width 0.1524)
				(type default)
			)
			(layer "B.SilkS")
		)
		(fp_line
			(start 0.7874 0.4064)
			(end 0.7874 -0.4064)
			(stroke
				(width 0.1524)
				(type default)
			)
			(layer "B.SilkS")
		)
		(fp_line
			(start -0.67945 -0.3048)
			(end -0.67945 0.3048)
			(stroke
				(width 0.1)
				(type default)
			)
			(layer "B.Fab")
		)
		(fp_line
			(start -0.67945 0.3048)
			(end -0.120396 0.3048)
			(stroke
				(width 0.1)
				(type default)
			)
			(layer "B.Fab")
		)
		(fp_line
			(start -0.12065 -0.3048)
			(end -0.67945 -0.3048)
			(stroke
				(width 0.1)
				(type default)
			)
			(layer "B.Fab")
		)
		(fp_line
			(start -0.12065 -0.2794)
			(end -0.12065 -0.3048)
			(stroke
				(width 0.1)
				(type default)
			)
			(layer "B.Fab")
		)
		(fp_line
			(start -0.120396 0.2794)
			(end 0.12065 0.2794)
			(stroke
				(width 0.1)
				(type default)
			)
			(layer "B.Fab")
		)
		(fp_line
			(start -0.120396 0.3048)
			(end -0.120396 0.2794)
			(stroke
				(width 0.1)
				(type default)
			)
			(layer "B.Fab")
		)
		(fp_line
			(start 0.12065 -0.305054)
			(end 0.12065 -0.2794)
			(stroke
				(width 0.1)
				(type default)
			)
			(layer "B.Fab")
		)
		(fp_line
			(start 0.12065 -0.2794)
			(end -0.12065 -0.2794)
			(stroke
				(width 0.1)
				(type default)
			)
			(layer "B.Fab")
		)
		(fp_line
			(start 0.12065 0.2794)
			(end 0.12065 0.3048)
			(stroke
				(width 0.1)
				(type default)
			)
			(layer "B.Fab")
		)
		(fp_line
			(start 0.12065 0.3048)
			(end 0.67945 0.3048)
			(stroke
				(width 0.1)
				(type default)
			)
			(layer "B.Fab")
		)
		(fp_line
			(start 0.67945 -0.305054)
			(end 0.12065 -0.305054)
			(stroke
				(width 0.1)
				(type default)
			)
			(layer "B.Fab")
		)
		(fp_line
			(start 0.67945 0.3048)
			(end 0.67945 -0.305054)
			(stroke
				(width 0.1)
				(type default)
			)
			(layer "B.Fab")
		)
		(pad "1" smd circle
			(at 0.40005 0 180)
			(size 0 0)
			(layers "B.Cu" "B.Mask" "B.Paste")
			(net "PVDDCR_CPU1_P1")
		)
		(pad "2" smd circle
			(at -0.40005 0 180)
			(size 0 0)
			(layers "B.Cu" "B.Mask" "B.Paste")
			(net "GND")
		)
	)
	(footprint ""
		(layer "B.Cu")
		(at 197.70725 -244.085364)
		(property "Reference" "R510"
			(at 0 0 0)
			(layer "B.SilkS")
			(hide yes)
			(effects
				(font
					(size 1.27 1.27)
				)
				(justify mirror)
			)
		)
		(property "Value" ""
			(at 0 0 0)
			(layer "B.Fab")
			(effects
				(font
					(size 1.27 1.27)
				)
				(justify mirror)
			)
		)
		(duplicate_pad_numbers_are_jumpers no)
		(fp_line
			(start -0.7874 -0.4064)
			(end -0.7874 0.4064)
			(stroke
				(width 0.1524)
				(type default)
			)
			(layer "B.SilkS")
		)
		(fp_line
			(start -0.7874 0.4064)
			(end 0.7874 0.4064)
			(stroke
				(width 0.1524)
				(type default)
			)
			(layer "B.SilkS")
		)
		(fp_line
			(start 0.7874 -0.4064)
			(end -0.7874 -0.4064)
			(stroke
				(width 0.1524)
				(type default)
			)
			(layer "B.SilkS")
		)
		(fp_line
			(start 0.7874 0.4064)
			(end 0.7874 -0.4064)
			(stroke
				(width 0.1524)
				(type default)
			)
			(layer "B.SilkS")
		)
		(fp_line
			(start -0.67945 -0.3048)
			(end -0.67945 0.3048)
			(stroke
				(width 0.1)
				(type default)
			)
			(layer "B.Fab")
		)
		(fp_line
			(start -0.67945 0.3048)
			(end -0.120396 0.3048)
			(stroke
				(width 0.1)
				(type default)
			)
			(layer "B.Fab")
		)
		(fp_line
			(start -0.12065 -0.3048)
			(end -0.67945 -0.3048)
			(stroke
				(width 0.1)
				(type default)
			)
			(layer "B.Fab")
		)
		(fp_line
			(start -0.12065 -0.2794)
			(end -0.12065 -0.3048)
			(stroke
				(width 0.1)
				(type default)
			)
			(layer "B.Fab")
		)
		(fp_line
			(start -0.120396 0.2794)
			(end 0.12065 0.2794)
			(stroke
				(width 0.1)
				(type default)
			)
			(layer "B.Fab")
		)
		(fp_line
			(start -0.120396 0.3048)
			(end -0.120396 0.2794)
			(stroke
				(width 0.1)
				(type default)
			)
			(layer "B.Fab")
		)
		(fp_line
			(start 0.12065 -0.305054)
			(end 0.12065 -0.2794)
			(stroke
				(width 0.1)
				(type default)
			)
			(layer "B.Fab")
		)
		(fp_line
			(start 0.12065 -0.2794)
			(end -0.12065 -0.2794)
			(stroke
				(width 0.1)
				(type default)
			)
			(layer "B.Fab")
		)
		(fp_line
			(start 0.12065 0.2794)
			(end 0.12065 0.3048)
			(stroke
				(width 0.1)
				(type default)
			)
			(layer "B.Fab")
		)
		(fp_line
			(start 0.12065 0.3048)
			(end 0.67945 0.3048)
			(stroke
				(width 0.1)
				(type default)
			)
			(layer "B.Fab")
		)
		(fp_line
			(start 0.67945 -0.305054)
			(end 0.12065 -0.305054)
			(stroke
				(width 0.1)
				(type default)
			)
			(layer "B.Fab")
		)
		(fp_line
			(start 0.67945 0.3048)
			(end 0.67945 -0.305054)
			(stroke
				(width 0.1)
				(type default)
			)
			(layer "B.Fab")
		)
		(pad "1" smd circle
			(at 0.40005 0 180)
			(size 0 0)
			(layers "B.Cu" "B.Mask" "B.Paste")
			(net "M_K_CPU1_ALERT_N")
		)
		(pad "2" smd circle
			(at -0.40005 0 180)
			(size 0 0)
			(layers "B.Cu" "B.Mask" "B.Paste")
			(net "M_K_CPU1_ALERT_R_N")
		)
	)
	(footprint ""
		(layer "B.Cu")
		(at 59.563762 -347.780356 -90)
		(property "Reference" "PR264"
			(at 0 0 90)
			(layer "B.SilkS")
			(hide yes)
			(effects
				(font
					(size 1.27 1.27)
				)
				(justify mirror)
			)
		)
		(property "Value" ""
			(at 0 0 90)
			(layer "B.Fab")
			(effects
				(font
					(size 1.27 1.27)
				)
				(justify mirror)
			)
		)
		(duplicate_pad_numbers_are_jumpers no)
		(fp_line
			(start -0.7874 0.4064)
			(end 0.7874 0.4064)
			(stroke
				(width 0.1524)
				(type default)
			)
			(layer "B.SilkS")
		)
		(fp_line
			(start 0.7874 0.4064)
			(end 0.7874 -0.4064)
			(stroke
				(width 0.1524)
				(type default)
			)
			(layer "B.SilkS")
		)
		(fp_line
			(start -0.7874 -0.4064)
			(end -0.7874 0.4064)
			(stroke
				(width 0.1524)
				(type default)
			)
			(layer "B.SilkS")
		)
		(fp_line
			(start 0.7874 -0.4064)
			(end -0.7874 -0.4064)
			(stroke
				(width 0.1524)
				(type default)
			)
			(layer "B.SilkS")
		)
		(fp_line
			(start -0.67945 0.3048)
			(end -0.120396 0.3048)
			(stroke
				(width 0.1)
				(type default)
			)
			(layer "B.Fab")
		)
		(fp_line
			(start -0.120396 0.3048)
			(end -0.120396 0.2794)
			(stroke
				(width 0.1)
				(type default)
			)
			(layer "B.Fab")
		)
		(fp_line
			(start 0.12065 0.3048)
			(end 0.67945 0.3048)
			(stroke
				(width 0.1)
				(type default)
			)
			(layer "B.Fab")
		)
		(fp_line
			(start 0.67945 0.3048)
			(end 0.67945 -0.305054)
			(stroke
				(width 0.1)
				(type default)
			)
			(layer "B.Fab")
		)
		(fp_line
			(start -0.120396 0.2794)
			(end 0.12065 0.2794)
			(stroke
				(width 0.1)
				(type default)
			)
			(layer "B.Fab")
		)
		(fp_line
			(start 0.12065 0.2794)
			(end 0.12065 0.3048)
			(stroke
				(width 0.1)
				(type default)
			)
			(layer "B.Fab")
		)
		(fp_line
			(start -0.12065 -0.2794)
			(end -0.12065 -0.3048)
			(stroke
				(width 0.1)
				(type default)
			)
			(layer "B.Fab")
		)
		(fp_line
			(start 0.12065 -0.2794)
			(end -0.12065 -0.2794)
			(stroke
				(width 0.1)
				(type default)
			)
			(layer "B.Fab")
		)
		(fp_line
			(start -0.67945 -0.3048)
			(end -0.67945 0.3048)
			(stroke
				(width 0.1)
				(type default)
			)
			(layer "B.Fab")
		)
		(fp_line
			(start -0.12065 -0.3048)
			(end -0.67945 -0.3048)
			(stroke
				(width 0.1)
				(type default)
			)
			(layer "B.Fab")
		)
		(fp_line
			(start 0.12065 -0.305054)
			(end 0.12065 -0.2794)
			(stroke
				(width 0.1)
				(type default)
			)
			(layer "B.Fab")
		)
		(fp_line
			(start 0.67945 -0.305054)
			(end 0.12065 -0.305054)
			(stroke
				(width 0.1)
				(type default)
			)
			(layer "B.Fab")
		)
		(pad "1" smd circle
			(at 0.40005 0 90)
			(size 0 0)
			(layers "B.Cu" "B.Mask" "B.Paste")
			(net "PVDDCR_CPU1_P1_PVCC")
		)
		(pad "2" smd circle
			(at -0.40005 0 90)
			(size 0 0)
			(layers "B.Cu" "B.Mask" "B.Paste")
			(net "PVDDCR_CPU1_P1_VCC4")
		)
	)
	(footprint ""
		(layer "B.Cu")
		(at 363.034834 -398.055084 90)
		(property "Reference" "C1028"
			(at 0 0 90)
			(layer "B.SilkS")
			(hide yes)
			(effects
				(font
					(size 1.27 1.27)
				)
				(justify mirror)
			)
		)
		(property "Value" ""
			(at 0 0 90)
			(layer "B.Fab")
			(effects
				(font
					(size 1.27 1.27)
				)
				(justify mirror)
			)
		)
		(duplicate_pad_numbers_are_jumpers no)
		(fp_line
			(start 1.524 -0.762)
			(end -1.524 -0.762)
			(stroke
				(width 0.1524)
				(type default)
			)
			(layer "B.SilkS")
		)
		(fp_line
			(start -1.524 -0.762)
			(end -1.524 0.762)
			(stroke
				(width 0.1524)
				(type default)
			)
			(layer "B.SilkS")
		)
		(fp_line
			(start 1.524 0.762)
			(end 1.524 -0.762)
			(stroke
				(width 0.1524)
				(type default)
			)
			(layer "B.SilkS")
		)
		(fp_line
			(start -1.524 0.762)
			(end 1.524 0.762)
			(stroke
				(width 0.1524)
				(type default)
			)
			(layer "B.SilkS")
		)
		(fp_line
			(start 1.1049 -0.724916)
			(end 1.1049 0.724916)
			(stroke
				(width 0.1)
				(type default)
			)
			(layer "B.Fab")
		)
		(fp_line
			(start -1.1049 -0.724916)
			(end 1.1049 -0.724916)
			(stroke
				(width 0.1)
				(type default)
			)
			(layer "B.Fab")
		)
		(fp_line
			(start 1.1049 0.724916)
			(end -1.1049 0.724916)
			(stroke
				(width 0.1)
				(type default)
			)
			(layer "B.Fab")
		)
		(fp_line
			(start -1.1049 0.724916)
			(end -1.1049 -0.724916)
			(stroke
				(width 0.1)
				(type default)
			)
			(layer "B.Fab")
		)
		(pad "1" smd rect
			(at 0.889 0 90)
			(size 1.016 1.27)
			(layers "B.Cu" "B.Mask" "B.Paste")
			(net "P0V9_CPU0_RT_2D")
		)
		(pad "2" smd rect
			(at -0.889 0 90)
			(size 1.016 1.27)
			(layers "B.Cu" "B.Mask" "B.Paste")
			(net "GND")
		)
	)
	(footprint ""
		(layer "B.Cu")
		(at 331.793342 -393.96416 180)
		(property "Reference" "R1031"
			(at 0 0 0)
			(layer "B.SilkS")
			(hide yes)
			(effects
				(font
					(size 1.27 1.27)
				)
				(justify mirror)
			)
		)
		(property "Value" ""
			(at 0 0 0)
			(layer "B.Fab")
			(effects
				(font
					(size 1.27 1.27)
				)
				(justify mirror)
			)
		)
		(duplicate_pad_numbers_are_jumpers no)
		(fp_line
			(start 0.32512 0.175006)
			(end 0.32512 -0.175006)
			(stroke
				(width 0.1)
				(type default)
			)
			(layer "B.Fab")
		)
		(fp_line
			(start 0.32512 -0.175006)
			(end -0.32512 -0.175006)
			(stroke
				(width 0.1)
				(type default)
			)
			(layer "B.Fab")
		)
		(fp_line
			(start -0.32512 0.175006)
			(end 0.32512 0.175006)
			(stroke
				(width 0.1)
				(type default)
			)
			(layer "B.Fab")
		)
		(fp_line
			(start -0.32512 -0.175006)
			(end -0.32512 0.175006)
			(stroke
				(width 0.1)
				(type default)
			)
			(layer "B.Fab")
		)
		(pad "1" smd rect
			(at 0.2667 0)
			(size 0.3048 0.381)
			(layers "B.Cu" "B.Mask" "B.Paste")
			(net "TEST0_RT_CPU0_P1")
		)
		(pad "2" smd rect
			(at -0.2667 0 180)
			(size 0.3048 0.381)
			(layers "B.Cu" "B.Mask" "B.Paste")
			(net "GND")
		)
	)
)
